# T6G (Grand Teton) — schematic netlist excerpt (pin names and nets, part order shuffled) for the footprints in the layout excerpt that follows; sources: Cadence DE-HDL packaged netlist, KiCad conversion of 04192023_DAF0TMB3IC0_F0TG_MB_C_brd_V02_OCP.brd

C2638  Q_CAP  22UF 4V 20% X6S  pkg C0402  page 70 : A = PVDDIO_P0 ; B = GND
R6225  Q_RES  33.2 1% EMPTY  pkg 0402LF  page 176 : A = SMB_USB_CPU0_HUB1_SDA ; B = SMB_USB_CPU0_HUB1_SDA_R2

(kicad_pcb
	(version 20260206)
	(generator "pcbnew")
	(generator_version "10.0")
	(general
		(thickness 1.6)
		(legacy_teardrops no)
	)
	(paper "A4")
	(title_block
		(title "04192023_DAF0TMB3IC0_F0TG_MB_C_brd_V02_OCP.brd")
		(comment 1 "Grand Teton / footprints 7613-7614 of 8354")
	)
	(layers
		(0 "F.Cu" signal "TOP")
		(4 "In1.Cu" signal "GND")
		(6 "In2.Cu" signal "IN1")
		(8 "In3.Cu" signal "GND1")
		(10 "In4.Cu" signal "IN2")
		(12 "In5.Cu" signal "GND2")
		(14 "In6.Cu" signal "IN3")
		(16 "In7.Cu" signal "GND3")
		(18 "In8.Cu" signal "VCC")
		(20 "In9.Cu" signal "VCC1")
		(22 "In10.Cu" signal "GND4")
		(24 "In11.Cu" signal "IN4")
		(26 "In12.Cu" signal "GND5")
		(28 "In13.Cu" signal "IN5")
		(30 "In14.Cu" signal "GND6")
		(32 "In15.Cu" signal "IN6")
		(34 "In16.Cu" signal "GND7")
		(2 "B.Cu" signal "BOTTOM")
		(9 "F.Adhes" user "F.Adhesive")
		(11 "B.Adhes" user "B.Adhesive")
		(13 "F.Paste" user "Package Geometry/Pastemask Top")
		(15 "B.Paste" user "Package Geometry/Pastemask Bottom")
		(5 "F.SilkS" user "Ref Des/Silkscreen Top")
		(7 "B.SilkS" user "Ref Des/Silkscreen Bottom")
		(1 "F.Mask" user "Board Geometry/Soldermask Top")
		(3 "B.Mask" user "Board Geometry/Soldermask Bottom")
		(17 "Dwgs.User" user "User.Drawings")
		(19 "Cmts.User" user "User.Comments")
		(21 "Eco1.User" user "User.Eco1")
		(23 "Eco2.User" user "User.Eco2")
		(25 "Edge.Cuts" user "Board Geometry/Outline")
		(27 "Margin" user)
		(31 "F.CrtYd" user "Package Geometry/Place Bound Top")
		(29 "B.CrtYd" user "Package Geometry/Place Bound Bottom")
		(35 "F.Fab" user "Ref Des/Assembly Top")
		(33 "B.Fab" user "Ref Des/Assembly Bottom")
	)
	(footprint ""
		(layer "B.Cu")
		(at 113.71834 -61.76391 -90)
		(property "Reference" "R6225"
			(at 0 0 90)
			(layer "B.SilkS")
			(hide yes)
			(effects
				(font
					(size 1.27 1.27)
				)
				(justify mirror)
			)
		)
		(property "Value" ""
			(at 0 0 90)
			(layer "B.Fab")
			(effects
				(font
					(size 1.27 1.27)
				)
				(justify mirror)
			)
		)
		(duplicate_pad_numbers_are_jumpers no)
		(fp_line
			(start -0.7874 0.4064)
			(end 0.7874 0.4064)
			(stroke
				(width 0.1524)
				(type default)
			)
			(layer "B.SilkS")
		)
		(fp_line
			(start 0.7874 0.4064)
			(end 0.7874 -0.4064)
			(stroke
				(width 0.1524)
				(type default)
			)
			(layer "B.SilkS")
		)
		(fp_line
			(start -0.7874 -0.4064)
			(end -0.7874 0.4064)
			(stroke
				(width 0.1524)
				(type default)
			)
			(layer "B.SilkS")
		)
		(fp_line
			(start 0.7874 -0.4064)
			(end -0.7874 -0.4064)
			(stroke
				(width 0.1524)
				(type default)
			)
			(layer "B.SilkS")
		)
		(fp_line
			(start -0.67945 0.3048)
			(end -0.120396 0.3048)
			(stroke
				(width 0.1)
				(type default)
			)
			(layer "B.Fab")
		)
		(fp_line
			(start -0.120396 0.3048)
			(end -0.120396 0.2794)
			(stroke
				(width 0.1)
				(type default)
			)
			(layer "B.Fab")
		)
		(fp_line
			(start 0.12065 0.3048)
			(end 0.67945 0.3048)
			(stroke
				(width 0.1)
				(type default)
			)
			(layer "B.Fab")
		)
		(fp_line
			(start 0.67945 0.3048)
			(end 0.67945 -0.305054)
			(stroke
				(width 0.1)
				(type default)
			)
			(layer "B.Fab")
		)
		(fp_line
			(start -0.120396 0.2794)
			(end 0.12065 0.2794)
			(stroke
				(width 0.1)
				(type default)
			)
			(layer "B.Fab")
		)
		(fp_line
			(start 0.12065 0.2794)
			(end 0.12065 0.3048)
			(stroke
				(width 0.1)
				(type default)
			)
			(layer "B.Fab")
		)
		(fp_line
			(start -0.12065 -0.2794)
			(end -0.12065 -0.3048)
			(stroke
				(width 0.1)
				(type default)
			)
			(layer "B.Fab")
		)
		(fp_line
			(start 0.12065 -0.2794)
			(end -0.12065 -0.2794)
			(stroke
				(width 0.1)
				(type default)
			)
			(layer "B.Fab")
		)
		(fp_line
			(start -0.67945 -0.3048)
			(end -0.67945 0.3048)
			(stroke
				(width 0.1)
				(type default)
			)
			(layer "B.Fab")
		)
		(fp_line
			(start -0.12065 -0.3048)
			(end -0.67945 -0.3048)
			(stroke
				(width 0.1)
				(type default)
			)
			(layer "B.Fab")
		)
		(fp_line
			(start 0.12065 -0.305054)
			(end 0.12065 -0.2794)
			(stroke
				(width 0.1)
				(type default)
			)
			(layer "B.Fab")
		)
		(fp_line
			(start 0.67945 -0.305054)
			(end 0.12065 -0.305054)
			(stroke
				(width 0.1)
				(type default)
			)
			(layer "B.Fab")
		)
		(pad "1" smd circle
			(at 0.40005 0 90)
			(size 0 0)
			(layers "B.Cu" "B.Mask" "B.Paste")
			(net "SMB_USB_CPU0_HUB1_SDA")
		)
		(pad "2" smd circle
			(at -0.40005 0 90)
			(size 0 0)
			(layers "B.Cu" "B.Mask" "B.Paste")
			(net "SMB_USB_CPU0_HUB1_SDA_R2")
		)
	)
	(footprint ""
		(layer "B.Cu")
		(at 353.900232 -258.405122 180)
		(property "Reference" "C2638"
			(at 0 0 0)
			(layer "B.SilkS")
			(hide yes)
			(effects
				(font
					(size 1.27 1.27)
				)
				(justify mirror)
			)
		)
		(property "Value" ""
			(at 0 0 0)
			(layer "B.Fab")
			(effects
				(font
					(size 1.27 1.27)
				)
				(justify mirror)
			)
		)
		(duplicate_pad_numbers_are_jumpers no)
		(fp_line
			(start 0.7874 0.4064)
			(end 0.7874 -0.4064)
			(stroke
				(width 0.1524)
				(type default)
			)
			(layer "B.SilkS")
		)
		(fp_line
			(start 0.7874 -0.4064)
			(end -0.7874 -0.4064)
			(stroke
				(width 0.1524)
				(type default)
			)
			(layer "B.SilkS")
		)
		(fp_line
			(start -0.7874 0.4064)
			(end 0.7874 0.4064)
			(stroke
				(width 0.1524)
				(type default)
			)
			(layer "B.SilkS")
		)
		(fp_line
			(start -0.7874 -0.4064)
			(end -0.7874 0.4064)
			(stroke
				(width 0.1524)
				(type default)
			)
			(layer "B.SilkS")
		)
		(fp_line
			(start 0.67945 0.3048)
			(end 0.67945 -0.305054)
			(stroke
				(width 0.1)
				(type default)
			)
			(layer "B.Fab")
		)
		(fp_line
			(start 0.67945 -0.305054)
			(end 0.12065 -0.305054)
			(stroke
				(width 0.1)
				(type default)
			)
			(layer "B.Fab")
		)
		(fp_line
			(start 0.12065 0.3048)
			(end 0.67945 0.3048)
			(stroke
				(width 0.1)
				(type default)
			)
			(layer "B.Fab")
		)
		(fp_line
			(start 0.12065 0.2794)
			(end 0.12065 0.3048)
			(stroke
				(width 0.1)
				(type default)
			)
			(layer "B.Fab")
		)
		(fp_line
			(start 0.12065 -0.2794)
			(end -0.12065 -0.2794)
			(stroke
				(width 0.1)
				(type default)
			)
			(layer "B.Fab")
		)
		(fp_line
			(start 0.12065 -0.305054)
			(end 0.12065 -0.2794)
			(stroke
				(width 0.1)
				(type default)
			)
			(layer "B.Fab")
		)
		(fp_line
			(start -0.120396 0.3048)
			(end -0.120396 0.2794)
			(stroke
				(width 0.1)
				(type default)
			)
			(layer "B.Fab")
		)
		(fp_line
			(start -0.120396 0.2794)
			(end 0.12065 0.2794)
			(stroke
				(width 0.1)
				(type default)
			)
			(layer "B.Fab")
		)
		(fp_line
			(start -0.12065 -0.2794)
			(end -0.12065 -0.3048)
			(stroke
				(width 0.1)
				(type default)
			)
			(layer "B.Fab")
		)
		(fp_line
			(start -0.12065 -0.3048)
			(end -0.67945 -0.3048)
			(stroke
				(width 0.1)
				(type default)
			)
			(layer "B.Fab")
		)
		(fp_line
			(start -0.67945 0.3048)
			(end -0.120396 0.3048)
			(stroke
				(width 0.1)
				(type default)
			)
			(layer "B.Fab")
		)
		(fp_line
			(start -0.67945 -0.3048)
			(end -0.67945 0.3048)
			(stroke
				(width 0.1)
				(type default)
			)
			(layer "B.Fab")
		)
		(pad "1" smd circle
			(at 0.40005 0)
			(size 0 0)
			(layers "B.Cu" "B.Mask" "B.Paste")
			(net "PVDDIO_P0")
		)
		(pad "2" smd circle
			(at -0.40005 0)
			(size 0 0)
			(layers "B.Cu" "B.Mask" "B.Paste")
			(net "GND")
		)
	)
)
